(kicad_pcb
	(version 20260206)
	(generator "pcbnew")
	(generator_version "10.0")
	(general
		(thickness 1.6)
		(legacy_teardrops no)
	)
	(paper "A4")
	(title_block
		(title "Bryce Canyon_R.DPB_16317-1_OCP.brd")
		(comment 1 "Bryce Canyon / footprints 1462-1467 of 2099")
	)
	(layers
		(0 "F.Cu" signal "TOP")
		(4 "In1.Cu" signal "L2GND")
		(6 "In2.Cu" signal "L3")
		(8 "In3.Cu" signal "L4VCC")
		(10 "In4.Cu" signal "L5VCC")
		(12 "In5.Cu" signal "L6")
		(14 "In6.Cu" signal "L7GND")
		(2 "B.Cu" signal "BOTTOM")
		(9 "F.Adhes" user "F.Adhesive")
		(11 "B.Adhes" user "B.Adhesive")
		(13 "F.Paste" user "Package Geometry/Pastemask Top")
		(15 "B.Paste" user "Package Geometry/Pastemask Bottom")
		(5 "F.SilkS" user "Ref Des/Silkscreen Top")
		(7 "B.SilkS" user "Ref Des/Silkscreen Bottom")
		(1 "F.Mask" user "Board Geometry/Soldermask Top")
		(3 "B.Mask" user "Board Geometry/Soldermask Bottom")
		(17 "Dwgs.User" user "User.Drawings")
		(19 "Cmts.User" user "User.Comments")
		(21 "Eco1.User" user "User.Eco1")
		(23 "Eco2.User" user "User.Eco2")
		(25 "Edge.Cuts" user "Board Geometry/Outline")
		(27 "Margin" user)
		(31 "F.CrtYd" user "Package Geometry/Place Bound Top")
		(29 "B.CrtYd" user "Package Geometry/Place Bound Bottom")
		(35 "F.Fab" user "Ref Des/Assembly Top")
		(33 "B.Fab" user "Ref Des/Assembly Bottom")
	)
	(footprint ""
		(layer "F.Cu")
		(at 175.26 -369.189 180)
		(property "Reference" "U21"
			(at 0 0 180)
			(layer "F.SilkS")
			(hide yes)
			(effects
				(font
					(size 1.27 1.27)
				)
			)
		)
		(property "Value" "ADM1278-2ACPZ-RL-1-GP"
			(at -4.7625 -7.4422 180)
			(unlocked yes)
			(layer "F.Fab")
			(hide yes)
			(effects
				(font
					(size 1.016 1.016)
					(thickness 0.1524)
				)
			)
		)
		(property "Device Type" "QFN32-G3D45-UH32"
			(at -4.7625 -8.9662 180)
			(unlocked yes)
			(layer "F.Fab")
			(hide yes)
			(effects
				(font
					(size 1.016 1.016)
					(thickness 0.1524)
				)
			)
		)
		(duplicate_pad_numbers_are_jumpers no)
		(fp_line
			(start 4.0513 -0.749808)
			(end 3.2893 -0.749808)
			(stroke
				(width 0.1524)
				(type default)
			)
			(layer "F.SilkS")
		)
		(fp_line
			(start 3.7973 1.749552)
			(end 3.2893 1.749552)
			(stroke
				(width 0.1524)
				(type default)
			)
			(layer "F.SilkS")
		)
		(fp_line
			(start 3.5179 3.5179)
			(end 2.2479 3.5179)
			(stroke
				(width 0.1524)
				(type default)
			)
			(layer "F.SilkS")
		)
		(fp_line
			(start 3.5179 2.2479)
			(end 3.5179 3.5179)
			(stroke
				(width 0.1524)
				(type default)
			)
			(layer "F.SilkS")
		)
		(fp_line
			(start -0.250698 4.0513)
			(end -0.250698 3.2893)
			(stroke
				(width 0.1524)
				(type default)
			)
			(layer "F.SilkS")
		)
		(fp_line
			(start -0.250698 -3.7973)
			(end -0.250698 -3.2893)
			(stroke
				(width 0.1524)
				(type default)
			)
			(layer "F.SilkS")
		)
		(fp_line
			(start -3.5179 3.5179)
			(end -2.2479 3.5179)
			(stroke
				(width 0.1524)
				(type default)
			)
			(layer "F.SilkS")
		)
		(fp_line
			(start -3.5179 2.2479)
			(end -3.5179 3.5179)
			(stroke
				(width 0.1524)
				(type default)
			)
			(layer "F.SilkS")
		)
		(fp_line
			(start -3.5179 -2.2479)
			(end -3.5179 -3.5179)
			(stroke
				(width 0.1524)
				(type default)
			)
			(layer "F.SilkS")
		)
		(fp_line
			(start -3.5179 -3.5179)
			(end -2.2479 -3.5179)
			(stroke
				(width 0.1524)
				(type default)
			)
			(layer "F.SilkS")
		)
		(fp_line
			(start -3.7973 1.24968)
			(end -3.2893 1.24968)
			(stroke
				(width 0.1524)
				(type default)
			)
			(layer "F.SilkS")
		)
		(fp_line
			(start -4.0513 -1.24968)
			(end -3.2893 -1.24968)
			(stroke
				(width 0.1524)
				(type default)
			)
			(layer "F.SilkS")
		)
		(fp_poly
			(pts
				(xy 2.2479 -3.5179) (xy 3.5179 -2.2479) (xy 3.5179 -3.5179)
			)
			(stroke
				(width 0)
				(type default)
			)
			(fill yes)
			(layer "F.SilkS")
		)
		(fp_rect
			(start -2.5019 2.5019)
			(end 2.5019 -2.5019)
			(stroke
				(width 0)
				(type default)
			)
			(fill no)
			(layer "F.CrtYd")
		)
		(fp_poly
			(pts
				(xy -3.5179 3.5179) (xy -3.5179 -3.5179) (xy 3.5179 -3.5179) (xy 3.5179 3.5179) (xy -2.49682 3.5179)
				(xy -2.49682 2.5019) (xy 2.5019 2.5019) (xy 2.5019 -2.5019) (xy -2.5019 -2.5019) (xy -2.5019 3.5179)
			)
			(stroke
				(width 0)
				(type default)
			)
			(fill no)
			(layer "F.CrtYd")
		)
		(fp_rect
			(start -3.5179 3.5179)
			(end 3.5179 -3.5179)
			(stroke
				(width 0)
				(type default)
			)
			(fill no)
			(layer "F.Fab")
		)
		(pad "1" smd rect
			(at 1.75006 -2.5527 180)
			(size 0.3048 0.9144)
			(layers "F.Cu" "F.Mask" "F.Paste")
			(net "MB0_PSET_R")
		)
		(pad "2" smd rect
			(at 1.249934 -2.4765 180)
			(size 0.3048 1.0668)
			(layers "F.Cu" "F.Mask" "F.Paste")
			(net "MB0_VCAP_R")
		)
		(pad "3" smd rect
			(at 0.750062 -2.4765 180)
			(size 0.3048 1.0668)
			(layers "F.Cu" "F.Mask" "F.Paste")
			(net "MB0_ISET_R")
		)
		(pad "4" smd rect
			(at 0.249936 -2.4765 180)
			(size 0.3048 1.0668)
			(layers "F.Cu" "F.Mask" "F.Paste")
			(net "MB0_ISTART_R")
		)
		(pad "5" smd rect
			(at -0.249936 -2.4765 180)
			(size 0.3048 1.0668)
			(layers "F.Cu" "F.Mask" "F.Paste")
			(net "MB0_TIME_R")
		)
		(pad "6" smd rect
			(at -0.750062 -2.4765 180)
			(size 0.3048 1.0668)
			(layers "F.Cu" "F.Mask" "F.Paste")
			(net "Net_978")
		)
		(pad "7" smd rect
			(at -1.249934 -2.4765 180)
			(size 0.3048 1.0668)
			(layers "F.Cu" "F.Mask" "F.Paste")
			(net "MB0_CM_ADR1_R")
		)
		(pad "8" smd rect
			(at -1.75006 -2.5527 180)
			(size 0.3048 0.9144)
			(layers "F.Cu" "F.Mask" "F.Paste")
			(net "MB0_CM_ADR2_R")
		)
		(pad "9" smd rect
			(at -2.5527 -1.75006 180)
			(size 0.9144 0.3048)
			(layers "F.Cu" "F.Mask" "F.Paste")
			(net "MB0_SPISS_PD")
		)
		(pad "10" smd rect
			(at -2.4765 -1.249934 180)
			(size 1.0668 0.3048)
			(layers "F.Cu" "F.Mask" "F.Paste")
			(net "Net_982")
		)
		(pad "11" smd rect
			(at -2.4765 -0.750062 180)
			(size 1.0668 0.3048)
			(layers "F.Cu" "F.Mask" "F.Paste")
			(net "Net_981")
		)
		(pad "12" smd rect
			(at -2.4765 -0.249936 180)
			(size 1.0668 0.3048)
			(layers "F.Cu" "F.Mask" "F.Paste")
			(net "MB0_HS_ENABLE")
		)
		(pad "13" smd rect
			(at -2.4765 0.249936 180)
			(size 1.0668 0.3048)
			(layers "F.Cu" "F.Mask" "F.Paste")
			(net "Net_980")
		)
		(pad "14" smd rect
			(at -2.4765 0.750062 180)
			(size 1.0668 0.3048)
			(layers "F.Cu" "F.Mask" "F.Paste")
			(net "Net_979")
		)
		(pad "15" smd rect
			(at -2.4765 1.249934 180)
			(size 1.0668 0.3048)
			(layers "F.Cu" "F.Mask" "F.Paste")
			(net "MB0_SDA_R")
		)
		(pad "16" smd rect
			(at -2.5527 1.75006 180)
			(size 0.9144 0.3048)
			(layers "F.Cu" "F.Mask" "F.Paste")
			(net "MB0_SCL_R")
		)
		(pad "17" smd rect
			(at -1.75006 2.5527 180)
			(size 0.3048 0.9144)
			(layers "F.Cu" "F.Mask" "F.Paste")
			(net "MB0_RETRY_R")
		)
		(pad "18" smd rect
			(at -1.249934 2.4765 180)
			(size 0.3048 1.0668)
			(layers "F.Cu" "F.Mask" "F.Paste")
			(net "P12V_IN_PGOOD")
		)
		(pad "19" smd rect
			(at -0.750062 2.4765 180)
			(size 0.3048 1.0668)
			(layers "F.Cu" "F.Mask" "F.Paste")
			(net "Net_983")
		)
		(pad "20" smd rect
			(at -0.249936 2.4765 180)
			(size 0.3048 1.0668)
			(layers "F.Cu" "F.Mask" "F.Paste")
			(net "MB0_CM_VOUT_R")
		)
		(pad "21" smd rect
			(at 0.249936 2.4765 180)
			(size 0.3048 1.0668)
			(layers "F.Cu" "F.Mask" "F.Paste")
			(net "MB0_P12V_PWGIN_R")
		)
		(pad "22" smd rect
			(at 0.750062 2.4765 180)
			(size 0.3048 1.0668)
			(layers "F.Cu" "F.Mask" "F.Paste")
			(net "AGND_CURRENT_MON")
		)
		(pad "23" smd rect
			(at 1.249934 2.4765 180)
			(size 0.3048 1.0668)
			(layers "F.Cu" "F.Mask" "F.Paste")
			(net "GND")
		)
		(pad "24" smd rect
			(at 1.75006 2.5527 180)
			(size 0.3048 0.9144)
			(layers "F.Cu" "F.Mask" "F.Paste")
			(net "MB0_CM_GATE")
		)
		(pad "25" smd rect
			(at 2.5527 1.75006 180)
			(size 0.9144 0.3048)
			(layers "F.Cu" "F.Mask" "F.Paste")
			(net "MB0_TEMP")
		)
		(pad "26" smd rect
			(at 2.4765 1.249934 180)
			(size 1.0668 0.3048)
			(layers "F.Cu" "F.Mask" "F.Paste")
			(net "MB0_CM_SENSE_N")
		)
		(pad "27" smd rect
			(at 2.4765 0.750062 180)
			(size 1.0668 0.3048)
			(layers "F.Cu" "F.Mask" "F.Paste")
			(net "MB0_HS_SENSE_N")
		)
		(pad "28" smd rect
			(at 2.4765 0.249936 180)
			(size 1.0668 0.3048)
			(layers "F.Cu" "F.Mask" "F.Paste")
			(net "MB0_HS_SENSE_P")
		)
		(pad "29" smd rect
			(at 2.4765 -0.249936 180)
			(size 1.0668 0.3048)
			(layers "F.Cu" "F.Mask" "F.Paste")
			(net "MB0_CM_SENSE_P")
		)
		(pad "30" smd rect
			(at 2.4765 -0.750062 180)
			(size 1.0668 0.3048)
			(layers "F.Cu" "F.Mask" "F.Paste")
			(net "MB0_P12V_HS")
		)
		(pad "31" smd rect
			(at 2.4765 -1.249934 180)
			(size 1.0668 0.3048)
			(layers "F.Cu" "F.Mask" "F.Paste")
			(net "MB0_CM_UV_R")
		)
		(pad "32" smd rect
			(at 2.5527 -1.75006 180)
			(size 0.9144 0.3048)
			(layers "F.Cu" "F.Mask" "F.Paste")
			(net "MB0_CM_OV_R")
		)
		(pad "33" smd rect
			(at 0 0 180)
			(size 3.4544 3.4544)
			(layers "F.Cu" "F.Mask" "F.Paste")
			(net "AGND_CURRENT_MON")
		)
	)
	(footprint ""
		(layer "F.Cu")
		(at 66.313812 -154.70505)
		(property "Reference" "TP86"
			(at 0 0 0)
			(layer "F.SilkS")
			(hide yes)
			(effects
				(font
					(size 1.27 1.27)
				)
			)
		)
		(property "Value" "*"
			(at -0.0508 -1.6764 0)
			(unlocked yes)
			(layer "F.Fab")
			(hide yes)
			(effects
				(font
					(size 1.016 1.016)
					(thickness 0.1524)
				)
			)
		)
		(property "Device Type" "TPAD32"
			(at -0.0508 -3.2004 0)
			(unlocked yes)
			(layer "F.Fab")
			(hide yes)
			(effects
				(font
					(size 1.016 1.016)
					(thickness 0.1524)
				)
			)
		)
		(duplicate_pad_numbers_are_jumpers no)
		(fp_poly
			(pts
				(arc
					(start 0.4064 0)
					(mid -0.4064 0)
					(end 0.4064 0)
				)
			)
			(stroke
				(width 0)
				(type default)
			)
			(fill no)
			(layer "F.CrtYd")
		)
		(fp_poly
			(pts
				(arc
					(start 0.7112 0)
					(mid -0.7112 0)
					(end 0.7112 0)
				)
			)
			(stroke
				(width 0)
				(type default)
			)
			(fill no)
			(layer "F.Fab")
		)
		(pad "1" smd circle
			(at 0 0)
			(size 0.8128 0.8128)
			(layers "F.Cu" "F.Mask" "F.Paste")
			(net "ACT_HDD_13")
		)
	)
	(footprint ""
		(layer "F.Cu")
		(at 52.64277 -110.565946 -90)
		(property "Reference" "C644"
			(at 0 0 270)
			(layer "F.SilkS")
			(hide yes)
			(effects
				(font
					(size 1.27 1.27)
				)
			)
		)
		(property "Value" "SC2200P50V2KX-2GP"
			(at 1.1811 -2.7051 270)
			(unlocked yes)
			(layer "F.Fab")
			(hide yes)
			(effects
				(font
					(size 1.016 1.016)
					(thickness 0.1524)
				)
			)
		)
		(property "Device Type" "C402H22"
			(at 1.1811 -4.2291 270)
			(unlocked yes)
			(layer "F.Fab")
			(hide yes)
			(effects
				(font
					(size 1.016 1.016)
					(thickness 0.1524)
				)
			)
		)
		(duplicate_pad_numbers_are_jumpers no)
		(fp_rect
			(start -0.4318 0.9525)
			(end 0.4318 -0.9525)
			(stroke
				(width 0)
				(type default)
			)
			(fill no)
			(layer "F.CrtYd")
		)
		(fp_rect
			(start -0.4318 0.9525)
			(end 0.4318 -0.9525)
			(stroke
				(width 0)
				(type default)
			)
			(fill no)
			(layer "F.Fab")
		)
		(pad "1" smd custom
			(at 0 -0.4445 270)
			(size 0.1524 0.1524)
			(layers "F.Cu" "F.Mask" "F.Paste")
			(net "P5V_B_2_LL")
			(options
				(clearance outline)
				(anchor circle)
			)
			(primitives
				(gr_poly
					(pts
						(arc
							(start 0.3048 -0.2032)
							(mid 0.275042 -0.275042)
							(end 0.2032 -0.3048)
						)
						(arc
							(start -0.2032 -0.3048)
							(mid -0.275042 -0.275042)
							(end -0.3048 -0.2032)
						)
						(arc
							(start -0.3048 0.2032)
							(mid -0.275042 0.275042)
							(end -0.2032 0.3048)
						)
						(arc
							(start 0.2032 0.3048)
							(mid 0.275042 0.275042)
							(end 0.3048 0.2032)
						)
					)
					(width 0)
					(fill yes)
				)
			)
		)
		(pad "2" smd custom
			(at 0 0.4445 270)
			(size 0.1524 0.1524)
			(layers "F.Cu" "F.Mask" "F.Paste")
			(net "P5V_B_2_SNB")
			(options
				(clearance outline)
				(anchor circle)
			)
			(primitives
				(gr_poly
					(pts
						(arc
							(start 0.3048 -0.2032)
							(mid 0.275042 -0.275042)
							(end 0.2032 -0.3048)
						)
						(arc
							(start -0.2032 -0.3048)
							(mid -0.275042 -0.275042)
							(end -0.3048 -0.2032)
						)
						(arc
							(start -0.3048 0.2032)
							(mid -0.275042 0.275042)
							(end -0.2032 0.3048)
						)
						(arc
							(start 0.2032 0.3048)
							(mid 0.275042 0.275042)
							(end 0.3048 0.2032)
						)
					)
					(width 0)
					(fill yes)
				)
			)
		)
	)
	(footprint ""
		(layer "F.Cu")
		(at 353.184714 -245.219474 -90)
		(property "Reference" "C119"
			(at 0 0 270)
			(layer "F.SilkS")
			(hide yes)
			(effects
				(font
					(size 1.27 1.27)
				)
			)
		)
		(property "Value" "SCD01U16V1KX-GP"
			(at -2.8321 -1.7399 270)
			(unlocked yes)
			(layer "F.Fab")
			(hide yes)
			(effects
				(font
					(size 1.016 1.016)
					(thickness 0.1524)
				)
			)
		)
		(property "Device Type" "C0201H13"
			(at -2.8321 -3.2639 270)
			(unlocked yes)
			(layer "F.Fab")
			(hide yes)
			(effects
				(font
					(size 1.016 1.016)
					(thickness 0.1524)
				)
			)
		)
		(duplicate_pad_numbers_are_jumpers no)
		(fp_rect
			(start -0.2794 0.6477)
			(end 0.2794 -0.6477)
			(stroke
				(width 0)
				(type default)
			)
			(fill no)
			(layer "F.CrtYd")
		)
		(fp_rect
			(start -0.2794 0.6477)
			(end 0.2794 -0.6477)
			(stroke
				(width 0)
				(type default)
			)
			(fill no)
			(layer "F.Fab")
		)
		(pad "1" smd custom
			(at 0 -0.2794 270)
			(size 0.0762 0.0762)
			(layers "F.Cu" "F.Mask" "F.Paste")
			(net "SAS_HDD_RX_N7")
			(options
				(clearance outline)
				(anchor circle)
			)
			(primitives
				(gr_poly
					(pts
						(arc
							(start 0.1524 -0.127)
							(mid 0.137521 -0.162921)
							(end 0.1016 -0.1778)
						)
						(arc
							(start -0.1016 -0.1778)
							(mid -0.137521 -0.162921)
							(end -0.1524 -0.127)
						)
						(arc
							(start -0.1524 0.127)
							(mid -0.137521 0.162921)
							(end -0.1016 0.1778)
						)
						(arc
							(start 0.1016 0.1778)
							(mid 0.137521 0.162921)
							(end 0.1524 0.127)
						)
					)
					(width 0)
					(fill yes)
				)
			)
		)
		(pad "2" smd custom
			(at 0 0.2794 270)
			(size 0.0762 0.0762)
			(layers "F.Cu" "F.Mask" "F.Paste")
			(net "PHY_SCC_B_TO_DRV_B_7_DN")
			(options
				(clearance outline)
				(anchor circle)
			)
			(primitives
				(gr_poly
					(pts
						(arc
							(start 0.1524 -0.127)
							(mid 0.137521 -0.162921)
							(end 0.1016 -0.1778)
						)
						(arc
							(start -0.1016 -0.1778)
							(mid -0.137521 -0.162921)
							(end -0.1524 -0.127)
						)
						(arc
							(start -0.1524 0.127)
							(mid -0.137521 0.162921)
							(end -0.1016 0.1778)
						)
						(arc
							(start 0.1016 0.1778)
							(mid 0.137521 0.162921)
							(end 0.1524 0.127)
						)
					)
					(width 0)
					(fill yes)
				)
			)
		)
	)
	(footprint ""
		(layer "F.Cu")
		(at 479.298 -45.339 180)
		(property "Reference" "C491"
			(at 0 0 180)
			(layer "F.SilkS")
			(hide yes)
			(effects
				(font
					(size 1.27 1.27)
				)
			)
		)
		(property "Value" "SC1U25V3KX-GP"
			(at 0 -2.8194 180)
			(unlocked yes)
			(layer "F.Fab")
			(hide yes)
			(effects
				(font
					(size 1.016 1.016)
					(thickness 0.1524)
				)
			)
		)
		(property "Device Type" "C603H36"
			(at 0 -4.3434 180)
			(unlocked yes)
			(layer "F.Fab")
			(hide yes)
			(effects
				(font
					(size 1.016 1.016)
					(thickness 0.1524)
				)
			)
		)
		(duplicate_pad_numbers_are_jumpers no)
		(fp_line
			(start 0.508 0)
			(end -0.508 0)
			(stroke
				(width 0.2032)
				(type default)
			)
			(layer "F.SilkS")
		)
		(fp_rect
			(start -0.5842 1.3335)
			(end 0.5842 -1.3335)
			(stroke
				(width 0)
				(type default)
			)
			(fill no)
			(layer "F.CrtYd")
		)
		(fp_rect
			(start -0.5842 1.3335)
			(end 0.5842 -1.3335)
			(stroke
				(width 0)
				(type default)
			)
			(fill no)
			(layer "F.Fab")
		)
		(pad "1" smd custom
			(at 0 -0.762 180)
			(size 0.2159 0.2159)
			(layers "F.Cu" "F.Mask" "F.Paste")
			(net "P12V_HDD35")
			(options
				(clearance outline)
				(anchor circle)
			)
			(primitives
				(gr_poly
					(pts
						(arc
							(start -0.3302 -0.4318)
							(mid -0.402042 -0.402042)
							(end -0.4318 -0.3302)
						)
						(arc
							(start -0.4318 0.3302)
							(mid -0.402042 0.402042)
							(end -0.3302 0.4318)
						)
						(arc
							(start 0.3302 0.4318)
							(mid 0.402042 0.402042)
							(end 0.4318 0.3302)
						)
						(arc
							(start 0.4318 -0.3302)
							(mid 0.402042 -0.402042)
							(end 0.3302 -0.4318)
						)
					)
					(width 0)
					(fill yes)
				)
			)
		)
		(pad "2" smd custom
			(at 0 0.762 180)
			(size 0.2159 0.2159)
			(layers "F.Cu" "F.Mask" "F.Paste")
			(net "GND")
			(options
				(clearance outline)
				(anchor circle)
			)
			(primitives
				(gr_poly
					(pts
						(arc
							(start -0.3302 -0.4318)
							(mid -0.402042 -0.402042)
							(end -0.4318 -0.3302)
						)
						(arc
							(start -0.4318 0.3302)
							(mid -0.402042 0.402042)
							(end -0.3302 0.4318)
						)
						(arc
							(start 0.3302 0.4318)
							(mid 0.402042 0.402042)
							(end 0.4318 0.3302)
						)
						(arc
							(start 0.4318 -0.3302)
							(mid 0.402042 -0.402042)
							(end 0.3302 -0.4318)
						)
					)
					(width 0)
					(fill yes)
				)
			)
		)
	)
	(footprint ""
		(layer "F.Cu")
		(at 465.3534 -99.3902)
		(property "Reference" "R458"
			(at 0 0 0)
			(layer "F.SilkS")
			(hide yes)
			(effects
				(font
					(size 1.27 1.27)
				)
			)
		)
		(property "Value" "91R3F-1-GP"
			(at -0.0254 -2.5146 0)
			(unlocked yes)
			(layer "F.Fab")
			(hide yes)
			(effects
				(font
					(size 1.016 1.016)
					(thickness 0.1524)
				)
			)
		)
		(property "Device Type" "R603H22"
			(at -0.0254 -4.0386 0)
			(unlocked yes)
			(layer "F.Fab")
			(hide yes)
			(effects
				(font
					(size 1.016 1.016)
					(thickness 0.1524)
				)
			)
		)
		(duplicate_pad_numbers_are_jumpers no)
		(fp_line
			(start -0.4826 0)
			(end -0.2032 0)
			(stroke
				(width 0.2032)
				(type default)
			)
			(layer "F.SilkS")
		)
		(fp_line
			(start 0.2032 0)
			(end 0.4826 0)
			(stroke
				(width 0.2032)
				(type default)
			)
			(layer "F.SilkS")
		)
		(fp_rect
			(start -0.5842 1.3335)
			(end 0.5842 -1.3335)
			(stroke
				(width 0)
				(type default)
			)
			(fill no)
			(layer "F.CrtYd")
		)
		(fp_rect
			(start -0.5842 1.3335)
			(end 0.5842 -1.3335)
			(stroke
				(width 0)
				(type default)
			)
			(fill no)
			(layer "F.Fab")
		)
		(pad "1" smd custom
			(at 0 -0.762)
			(size 0.2159 0.2159)
			(layers "F.Cu" "F.Mask" "F.Paste")
			(net "P5V_B_4")
			(options
				(clearance outline)
				(anchor circle)
			)
			(primitives
				(gr_poly
					(pts
						(arc
							(start -0.3302 -0.4318)
							(mid -0.402042 -0.402042)
							(end -0.4318 -0.3302)
						)
						(arc
							(start -0.4318 0.3302)
							(mid -0.402042 0.402042)
							(end -0.3302 0.4318)
						)
						(arc
							(start 0.3302 0.4318)
							(mid 0.402042 0.402042)
							(end 0.4318 0.3302)
						)
						(arc
							(start 0.4318 -0.3302)
							(mid 0.402042 -0.402042)
							(end 0.3302 -0.4318)
						)
					)
					(width 0)
					(fill yes)
				)
			)
		)
		(pad "2" smd custom
			(at 0 0.762)
			(size 0.2159 0.2159)
			(layers "F.Cu" "F.Mask" "F.Paste")
			(net "DRV_ACT_23")
			(options
				(clearance outline)
				(anchor circle)
			)
			(primitives
				(gr_poly
					(pts
						(arc
							(start -0.3302 -0.4318)
							(mid -0.402042 -0.402042)
							(end -0.4318 -0.3302)
						)
						(arc
							(start -0.4318 0.3302)
							(mid -0.402042 0.402042)
							(end -0.3302 0.4318)
						)
						(arc
							(start 0.3302 0.4318)
							(mid 0.402042 0.402042)
							(end 0.4318 0.3302)
						)
						(arc
							(start 0.4318 -0.3302)
							(mid 0.402042 -0.402042)
							(end 0.3302 -0.4318)
						)
					)
					(width 0)
					(fill yes)
				)
			)
		)
	)
)
